(kicad_pcb
	(version 20260206)
	(generator "pcbnew")
	(generator_version "10.0")
	(general
		(thickness 1.6)
		(legacy_teardrops no)
	)
	(paper "A4")
	(title_block
		(title "panther-plus-userver — 13130-1b_20150205.brd")
		(comment 1 "Honey Badger (Wiwynn) / footprint 894 of 1509 (DIMM1), pads 121-127 of 210")
	)
	(layers
		(0 "F.Cu" signal "TOP")
		(4 "In1.Cu" signal "L2")
		(6 "In2.Cu" signal "L3")
		(8 "In3.Cu" signal "L4")
		(10 "In4.Cu" signal "L5")
		(12 "In5.Cu" signal "L6")
		(14 "In6.Cu" signal "L7")
		(16 "In7.Cu" signal "L8")
		(18 "In8.Cu" signal "L9")
		(20 "In9.Cu" signal "L10")
		(22 "In10.Cu" signal "L11")
		(2 "B.Cu" signal "BOTTOM")
		(9 "F.Adhes" user "F.Adhesive")
		(11 "B.Adhes" user "B.Adhesive")
		(13 "F.Paste" user "Package Geometry/Pastemask Top")
		(15 "B.Paste" user "Package Geometry/Pastemask Bottom")
		(5 "F.SilkS" user "Ref Des/Silkscreen Top")
		(7 "B.SilkS" user "Ref Des/Silkscreen Bottom")
		(1 "F.Mask" user "Board Geometry/Soldermask Top")
		(3 "B.Mask" user "Board Geometry/Soldermask Bottom")
		(17 "Dwgs.User" user "User.Drawings")
		(19 "Cmts.User" user "User.Comments")
		(21 "Eco1.User" user "User.Eco1")
		(23 "Eco2.User" user "User.Eco2")
		(25 "Edge.Cuts" user "Board Geometry/Outline")
		(27 "Margin" user)
		(31 "F.CrtYd" user "Package Geometry/Place Bound Top")
		(29 "B.CrtYd" user "Package Geometry/Place Bound Bottom")
		(35 "F.Fab" user "Ref Des/Assembly Top")
		(33 "B.Fab" user "Ref Des/Assembly Bottom")
	)
	(footprint ""
		(layer "B.Cu")
		(at 158.500064 -66.699892 180)
		(property "Reference" "DIMM1"
			(at 0 0 0)
			(layer "B.SilkS")
			(hide yes)
			(effects
				(font
					(size 1.27 1.27)
				)
				(justify mirror)
			)
		)
		(property "Value" "DDR3-204P-142-COLAY-1-GP-U"
			(at 41.312338 -16.676878 180)
			(unlocked yes)
			(layer "B.Fab")
			(hide yes)
			(effects
				(font
					(size 1.016 1.016)
					(thickness 0.1524)
				)
				(justify mirror)
			)
		)
		(property "Device Type" "AS0A626-J8R6-7H-COLAY-1"
			(at 41.312338 -18.200878 180)
			(unlocked yes)
			(layer "B.Fab")
			(hide yes)
			(effects
				(font
					(size 1.016 1.016)
					(thickness 0.1524)
				)
				(justify mirror)
			)
		)
		(duplicate_pad_numbers_are_jumpers no)
		(pad "119" smd custom
			(at 6.150102 -4.100068)
			(size 0.1143 0.1143)
			(layers "B.Cu" "B.Mask" "B.Paste")
			(net "M_A_BS0")
			(options
				(clearance outline)
				(anchor circle)
			)
			(primitives
				(gr_poly
					(pts
						(xy 0 -0.9017) (xy -0.03175 -0.89916) (xy -0.0635 -0.889) (xy -0.09144 -0.87376) (xy -0.11684 -0.85344)
						(xy -0.13716 -0.82804) (xy -0.1524 -0.8001) (xy -0.16256 -0.76835) (xy -0.1651 -0.7366) (xy -0.1651 -0.19685)
						(xy -0.17272 -0.18923) (xy -0.17907 -0.18034) (xy -0.18669 -0.17145) (xy -0.19177 -0.16256) (xy -0.19812 -0.15367)
						(xy -0.20828 -0.13335) (xy -0.21971 -0.10287) (xy -0.22225 -0.09271) (xy -0.22479 -0.08128) (xy -0.22606 -0.07112)
						(xy -0.2286 -0.05969) (xy -0.2286 -0.01651) (xy -0.22606 -0.00508) (xy -0.22479 0.00508) (xy -0.22225 0.01651)
						(xy -0.21971 0.02667) (xy -0.20828 0.05715) (xy -0.19812 0.07747) (xy -0.19177 0.08636) (xy -0.18669 0.09525)
						(xy -0.17907 0.10414) (xy -0.17272 0.11303) (xy -0.1651 0.12065) (xy -0.1651 0.7366) (xy -0.16256 0.76835)
						(xy -0.1524 0.8001) (xy -0.13716 0.82804) (xy -0.11684 0.85344) (xy -0.09144 0.87376) (xy -0.0635 0.889)
						(xy -0.03175 0.89916) (xy 0 0.9017) (xy 0.03175 0.89916) (xy 0.0635 0.889) (xy 0.09144 0.87376)
						(xy 0.11684 0.85344) (xy 0.13716 0.82804) (xy 0.1524 0.8001) (xy 0.16256 0.76835) (xy 0.1651 0.7366)
						(xy 0.1651 0.11938) (xy 0.17272 0.11176) (xy 0.19812 0.0762) (xy 0.2032 0.06604) (xy 0.20701 0.05715)
						(xy 0.21209 0.04699) (xy 0.2159 0.03683) (xy 0.21844 0.02667) (xy 0.22225 0.01524) (xy 0.22352 0.00508)
						(xy 0.22606 -0.00508) (xy 0.22733 -0.01651) (xy 0.22733 -0.02667) (xy 0.2286 -0.0381) (xy 0.22733 -0.04953)
						(xy 0.22733 -0.05969) (xy 0.22606 -0.07112) (xy 0.22352 -0.08128) (xy 0.22225 -0.09144) (xy 0.21844 -0.10287)
						(xy 0.2159 -0.11303) (xy 0.21209 -0.12319) (xy 0.20701 -0.13335) (xy 0.2032 -0.14224) (xy 0.19812 -0.1524)
						(xy 0.17272 -0.18796) (xy 0.1651 -0.19558) (xy 0.1651 -0.7366) (xy 0.16256 -0.76835) (xy 0.1524 -0.8001)
						(xy 0.13716 -0.82804) (xy 0.11684 -0.85344) (xy 0.09144 -0.87376) (xy 0.0635 -0.889) (xy 0.03175 -0.89916)
					)
					(width 0)
					(fill yes)
				)
			)
		)
		(pad "120" smd custom
			(at 6.450076 4.100068)
			(size 0.1143 0.1143)
			(layers "B.Cu" "B.Mask" "B.Paste")
			(net "Net_15")
			(options
				(clearance outline)
				(anchor circle)
			)
			(primitives
				(gr_poly
					(pts
						(xy 0 -0.9017) (xy -0.03175 -0.89916) (xy -0.0635 -0.889) (xy -0.09144 -0.87376) (xy -0.11684 -0.85344)
						(xy -0.13716 -0.82804) (xy -0.1524 -0.8001) (xy -0.16256 -0.76835) (xy -0.1651 -0.7366) (xy -0.1651 -0.11938)
						(xy -0.17272 -0.11176) (xy -0.19812 -0.0762) (xy -0.2032 -0.06604) (xy -0.20701 -0.05715) (xy -0.21209 -0.04699)
						(xy -0.2159 -0.03683) (xy -0.21844 -0.02667) (xy -0.22225 -0.01524) (xy -0.22352 -0.00508) (xy -0.22606 0.00508)
						(xy -0.22733 0.01651) (xy -0.22733 0.02667) (xy -0.2286 0.0381) (xy -0.22733 0.04953) (xy -0.22733 0.05969)
						(xy -0.22606 0.07112) (xy -0.22352 0.08128) (xy -0.22225 0.09144) (xy -0.21844 0.10287) (xy -0.2159 0.11303)
						(xy -0.21209 0.12319) (xy -0.20701 0.13335) (xy -0.2032 0.14224) (xy -0.19812 0.1524) (xy -0.17272 0.18796)
						(xy -0.1651 0.19558) (xy -0.1651 0.7366) (xy -0.16256 0.76835) (xy -0.1524 0.8001) (xy -0.13716 0.82804)
						(xy -0.11684 0.85344) (xy -0.09144 0.87376) (xy -0.0635 0.889) (xy -0.03175 0.89916) (xy 0 0.9017)
						(xy 0.03175 0.89916) (xy 0.0635 0.889) (xy 0.09144 0.87376) (xy 0.11684 0.85344) (xy 0.13716 0.82804)
						(xy 0.1524 0.8001) (xy 0.16256 0.76835) (xy 0.1651 0.7366) (xy 0.1651 0.19685) (xy 0.17272 0.18923)
						(xy 0.17907 0.18034) (xy 0.18669 0.17145) (xy 0.19177 0.16256) (xy 0.19812 0.15367) (xy 0.20828 0.13335)
						(xy 0.21971 0.10287) (xy 0.22225 0.09271) (xy 0.22479 0.08128) (xy 0.22606 0.07112) (xy 0.2286 0.05969)
						(xy 0.2286 0.01651) (xy 0.22606 0.00508) (xy 0.22479 -0.00508) (xy 0.22225 -0.01651) (xy 0.21971 -0.02667)
						(xy 0.20828 -0.05715) (xy 0.19812 -0.07747) (xy 0.19177 -0.08636) (xy 0.18669 -0.09525) (xy 0.17907 -0.10414)
						(xy 0.17272 -0.11303) (xy 0.1651 -0.12065) (xy 0.1651 -0.7366) (xy 0.16256 -0.76835) (xy 0.1524 -0.8001)
						(xy 0.13716 -0.82804) (xy 0.11684 -0.85344) (xy 0.09144 -0.87376) (xy 0.0635 -0.889) (xy 0.03175 -0.89916)
					)
					(width 0)
					(fill yes)
				)
			)
		)
		(pad "121" smd custom
			(at 6.75005 -4.100068)
			(size 0.1143 0.1143)
			(layers "B.Cu" "B.Mask" "B.Paste")
			(net "M_A_WE#")
			(options
				(clearance outline)
				(anchor circle)
			)
			(primitives
				(gr_poly
					(pts
						(xy 0 -0.9017) (xy -0.03175 -0.89916) (xy -0.0635 -0.889) (xy -0.09144 -0.87376) (xy -0.11684 -0.85344)
						(xy -0.13716 -0.82804) (xy -0.1524 -0.8001) (xy -0.16256 -0.76835) (xy -0.1651 -0.7366) (xy -0.1651 -0.44958)
						(xy -0.17272 -0.44196) (xy -0.19812 -0.4064) (xy -0.2032 -0.39624) (xy -0.20701 -0.38735) (xy -0.21209 -0.37719)
						(xy -0.2159 -0.36703) (xy -0.21844 -0.35687) (xy -0.22225 -0.34544) (xy -0.22352 -0.33528) (xy -0.22606 -0.32512)
						(xy -0.22733 -0.31369) (xy -0.22733 -0.30353) (xy -0.2286 -0.2921) (xy -0.22733 -0.28067) (xy -0.22733 -0.27051)
						(xy -0.22606 -0.25908) (xy -0.22352 -0.24892) (xy -0.22225 -0.23876) (xy -0.21844 -0.22733) (xy -0.2159 -0.21717)
						(xy -0.21209 -0.20701) (xy -0.20701 -0.19685) (xy -0.2032 -0.18796) (xy -0.19812 -0.1778) (xy -0.17272 -0.14224)
						(xy -0.1651 -0.13462) (xy -0.1651 0.7366) (xy -0.16256 0.76835) (xy -0.1524 0.8001) (xy -0.13716 0.82804)
						(xy -0.11684 0.85344) (xy -0.09144 0.87376) (xy -0.0635 0.889) (xy -0.03175 0.89916) (xy 0 0.9017)
						(xy 0.03175 0.89916) (xy 0.0635 0.889) (xy 0.09144 0.87376) (xy 0.11684 0.85344) (xy 0.13716 0.82804)
						(xy 0.1524 0.8001) (xy 0.16256 0.76835) (xy 0.1651 0.7366) (xy 0.1651 -0.13462) (xy 0.17272 -0.14224)
						(xy 0.19812 -0.1778) (xy 0.2032 -0.18796) (xy 0.20701 -0.19685) (xy 0.21209 -0.20701) (xy 0.2159 -0.21717)
						(xy 0.21844 -0.22733) (xy 0.22225 -0.23876) (xy 0.22352 -0.24892) (xy 0.22606 -0.25908) (xy 0.22733 -0.27051)
						(xy 0.22733 -0.28067) (xy 0.2286 -0.2921) (xy 0.22733 -0.30353) (xy 0.22733 -0.31369) (xy 0.22606 -0.32512)
						(xy 0.22352 -0.33528) (xy 0.22225 -0.34544) (xy 0.21844 -0.35687) (xy 0.2159 -0.36703) (xy 0.21209 -0.37719)
						(xy 0.20701 -0.38735) (xy 0.2032 -0.39624) (xy 0.19812 -0.4064) (xy 0.17272 -0.44196) (xy 0.1651 -0.44958)
						(xy 0.1651 -0.7366) (xy 0.16256 -0.76835) (xy 0.1524 -0.8001) (xy 0.13716 -0.82804) (xy 0.11684 -0.85344)
						(xy 0.09144 -0.87376) (xy 0.0635 -0.889) (xy 0.03175 -0.89916)
					)
					(width 0)
					(fill yes)
				)
			)
		)
		(pad "122" smd custom
			(at 7.050024 4.100068)
			(size 0.1143 0.1143)
			(layers "B.Cu" "B.Mask" "B.Paste")
			(net "M_A_RAS#")
			(options
				(clearance outline)
				(anchor circle)
			)
			(primitives
				(gr_poly
					(pts
						(xy 0 -0.9017) (xy -0.03175 -0.89916) (xy -0.0635 -0.889) (xy -0.09144 -0.87376) (xy -0.11684 -0.85344)
						(xy -0.13716 -0.82804) (xy -0.1524 -0.8001) (xy -0.16256 -0.76835) (xy -0.1651 -0.7366) (xy -0.1651 0.13462)
						(xy -0.17272 0.14224) (xy -0.19812 0.1778) (xy -0.2032 0.18796) (xy -0.20701 0.19685) (xy -0.21209 0.20701)
						(xy -0.2159 0.21717) (xy -0.21844 0.22733) (xy -0.22225 0.23876) (xy -0.22352 0.24892) (xy -0.22606 0.25908)
						(xy -0.22733 0.27051) (xy -0.22733 0.28067) (xy -0.2286 0.2921) (xy -0.22733 0.30353) (xy -0.22733 0.31369)
						(xy -0.22606 0.32512) (xy -0.22352 0.33528) (xy -0.22225 0.34544) (xy -0.21844 0.35687) (xy -0.2159 0.36703)
						(xy -0.21209 0.37719) (xy -0.20701 0.38735) (xy -0.2032 0.39624) (xy -0.19812 0.4064) (xy -0.17272 0.44196)
						(xy -0.1651 0.44958) (xy -0.1651 0.7366) (xy -0.16256 0.76835) (xy -0.1524 0.8001) (xy -0.13716 0.82804)
						(xy -0.11684 0.85344) (xy -0.09144 0.87376) (xy -0.0635 0.889) (xy -0.03175 0.89916) (xy 0 0.9017)
						(xy 0.03175 0.89916) (xy 0.0635 0.889) (xy 0.09144 0.87376) (xy 0.11684 0.85344) (xy 0.13716 0.82804)
						(xy 0.1524 0.8001) (xy 0.16256 0.76835) (xy 0.1651 0.7366) (xy 0.1651 0.44958) (xy 0.17272 0.44196)
						(xy 0.19812 0.4064) (xy 0.2032 0.39624) (xy 0.20701 0.38735) (xy 0.21209 0.37719) (xy 0.2159 0.36703)
						(xy 0.21844 0.35687) (xy 0.22225 0.34544) (xy 0.22352 0.33528) (xy 0.22606 0.32512) (xy 0.22733 0.31369)
						(xy 0.22733 0.30353) (xy 0.2286 0.2921) (xy 0.22733 0.28067) (xy 0.22733 0.27051) (xy 0.22606 0.25908)
						(xy 0.22352 0.24892) (xy 0.22225 0.23876) (xy 0.21844 0.22733) (xy 0.2159 0.21717) (xy 0.21209 0.20701)
						(xy 0.20701 0.19685) (xy 0.2032 0.18796) (xy 0.19812 0.1778) (xy 0.17272 0.14224) (xy 0.1651 0.13462)
						(xy 0.1651 -0.7366) (xy 0.16256 -0.76835) (xy 0.1524 -0.8001) (xy 0.13716 -0.82804) (xy 0.11684 -0.85344)
						(xy 0.09144 -0.87376) (xy 0.0635 -0.889) (xy 0.03175 -0.89916)
					)
					(width 0)
					(fill yes)
				)
			)
		)
		(pad "123" smd custom
			(at 7.349998 -4.100068)
			(size 0.1143 0.1143)
			(layers "B.Cu" "B.Mask" "B.Paste")
			(net "PV_VDDR")
			(options
				(clearance outline)
				(anchor circle)
			)
			(primitives
				(gr_poly
					(pts
						(xy 0 -0.9017) (xy -0.03175 -0.89916) (xy -0.0635 -0.889) (xy -0.09144 -0.87376) (xy -0.11684 -0.85344)
						(xy -0.13716 -0.82804) (xy -0.1524 -0.8001) (xy -0.16256 -0.76835) (xy -0.1651 -0.7366) (xy -0.1651 -0.19685)
						(xy -0.17272 -0.18923) (xy -0.17907 -0.18034) (xy -0.18669 -0.17145) (xy -0.19177 -0.16256) (xy -0.19812 -0.15367)
						(xy -0.20828 -0.13335) (xy -0.21971 -0.10287) (xy -0.22225 -0.09271) (xy -0.22479 -0.08128) (xy -0.22606 -0.07112)
						(xy -0.2286 -0.05969) (xy -0.2286 -0.01651) (xy -0.22606 -0.00508) (xy -0.22479 0.00508) (xy -0.22225 0.01651)
						(xy -0.21971 0.02667) (xy -0.20828 0.05715) (xy -0.19812 0.07747) (xy -0.19177 0.08636) (xy -0.18669 0.09525)
						(xy -0.17907 0.10414) (xy -0.17272 0.11303) (xy -0.1651 0.12065) (xy -0.1651 0.7366) (xy -0.16256 0.76835)
						(xy -0.1524 0.8001) (xy -0.13716 0.82804) (xy -0.11684 0.85344) (xy -0.09144 0.87376) (xy -0.0635 0.889)
						(xy -0.03175 0.89916) (xy 0 0.9017) (xy 0.03175 0.89916) (xy 0.0635 0.889) (xy 0.09144 0.87376)
						(xy 0.11684 0.85344) (xy 0.13716 0.82804) (xy 0.1524 0.8001) (xy 0.16256 0.76835) (xy 0.1651 0.7366)
						(xy 0.1651 0.11938) (xy 0.17272 0.11176) (xy 0.19812 0.0762) (xy 0.2032 0.06604) (xy 0.20701 0.05715)
						(xy 0.21209 0.04699) (xy 0.2159 0.03683) (xy 0.21844 0.02667) (xy 0.22225 0.01524) (xy 0.22352 0.00508)
						(xy 0.22606 -0.00508) (xy 0.22733 -0.01651) (xy 0.22733 -0.02667) (xy 0.2286 -0.0381) (xy 0.22733 -0.04953)
						(xy 0.22733 -0.05969) (xy 0.22606 -0.07112) (xy 0.22352 -0.08128) (xy 0.22225 -0.09144) (xy 0.21844 -0.10287)
						(xy 0.2159 -0.11303) (xy 0.21209 -0.12319) (xy 0.20701 -0.13335) (xy 0.2032 -0.14224) (xy 0.19812 -0.1524)
						(xy 0.17272 -0.18796) (xy 0.1651 -0.19558) (xy 0.1651 -0.7366) (xy 0.16256 -0.76835) (xy 0.1524 -0.8001)
						(xy 0.13716 -0.82804) (xy 0.11684 -0.85344) (xy 0.09144 -0.87376) (xy 0.0635 -0.889) (xy 0.03175 -0.89916)
					)
					(width 0)
					(fill yes)
				)
			)
		)
		(pad "124" smd custom
			(at 7.649972 4.100068)
			(size 0.1143 0.1143)
			(layers "B.Cu" "B.Mask" "B.Paste")
			(net "PV_VDDR")
			(options
				(clearance outline)
				(anchor circle)
			)
			(primitives
				(gr_poly
					(pts
						(xy 0 -0.9017) (xy -0.03175 -0.89916) (xy -0.0635 -0.889) (xy -0.09144 -0.87376) (xy -0.11684 -0.85344)
						(xy -0.13716 -0.82804) (xy -0.1524 -0.8001) (xy -0.16256 -0.76835) (xy -0.1651 -0.7366) (xy -0.1651 -0.11938)
						(xy -0.17272 -0.11176) (xy -0.19812 -0.0762) (xy -0.2032 -0.06604) (xy -0.20701 -0.05715) (xy -0.21209 -0.04699)
						(xy -0.2159 -0.03683) (xy -0.21844 -0.02667) (xy -0.22225 -0.01524) (xy -0.22352 -0.00508) (xy -0.22606 0.00508)
						(xy -0.22733 0.01651) (xy -0.22733 0.02667) (xy -0.2286 0.0381) (xy -0.22733 0.04953) (xy -0.22733 0.05969)
						(xy -0.22606 0.07112) (xy -0.22352 0.08128) (xy -0.22225 0.09144) (xy -0.21844 0.10287) (xy -0.2159 0.11303)
						(xy -0.21209 0.12319) (xy -0.20701 0.13335) (xy -0.2032 0.14224) (xy -0.19812 0.1524) (xy -0.17272 0.18796)
						(xy -0.1651 0.19558) (xy -0.1651 0.7366) (xy -0.16256 0.76835) (xy -0.1524 0.8001) (xy -0.13716 0.82804)
						(xy -0.11684 0.85344) (xy -0.09144 0.87376) (xy -0.0635 0.889) (xy -0.03175 0.89916) (xy 0 0.9017)
						(xy 0.03175 0.89916) (xy 0.0635 0.889) (xy 0.09144 0.87376) (xy 0.11684 0.85344) (xy 0.13716 0.82804)
						(xy 0.1524 0.8001) (xy 0.16256 0.76835) (xy 0.1651 0.7366) (xy 0.1651 0.19685) (xy 0.17272 0.18923)
						(xy 0.17907 0.18034) (xy 0.18669 0.17145) (xy 0.19177 0.16256) (xy 0.19812 0.15367) (xy 0.20828 0.13335)
						(xy 0.21971 0.10287) (xy 0.22225 0.09271) (xy 0.22479 0.08128) (xy 0.22606 0.07112) (xy 0.2286 0.05969)
						(xy 0.2286 0.01651) (xy 0.22606 0.00508) (xy 0.22479 -0.00508) (xy 0.22225 -0.01651) (xy 0.21971 -0.02667)
						(xy 0.20828 -0.05715) (xy 0.19812 -0.07747) (xy 0.19177 -0.08636) (xy 0.18669 -0.09525) (xy 0.17907 -0.10414)
						(xy 0.17272 -0.11303) (xy 0.1651 -0.12065) (xy 0.1651 -0.7366) (xy 0.16256 -0.76835) (xy 0.1524 -0.8001)
						(xy 0.13716 -0.82804) (xy 0.11684 -0.85344) (xy 0.09144 -0.87376) (xy 0.0635 -0.889) (xy 0.03175 -0.89916)
					)
					(width 0)
					(fill yes)
				)
			)
		)
		(pad "125" smd custom
			(at 7.949946 -4.100068)
			(size 0.1143 0.1143)
			(layers "B.Cu" "B.Mask" "B.Paste")
			(net "M_A_CAS#")
			(options
				(clearance outline)
				(anchor circle)
			)
			(primitives
				(gr_poly
					(pts
						(xy 0 -0.9017) (xy -0.03175 -0.89916) (xy -0.0635 -0.889) (xy -0.09144 -0.87376) (xy -0.11684 -0.85344)
						(xy -0.13716 -0.82804) (xy -0.1524 -0.8001) (xy -0.16256 -0.76835) (xy -0.1651 -0.7366) (xy -0.1651 -0.44958)
						(xy -0.17272 -0.44196) (xy -0.19812 -0.4064) (xy -0.2032 -0.39624) (xy -0.20701 -0.38735) (xy -0.21209 -0.37719)
						(xy -0.2159 -0.36703) (xy -0.21844 -0.35687) (xy -0.22225 -0.34544) (xy -0.22352 -0.33528) (xy -0.22606 -0.32512)
						(xy -0.22733 -0.31369) (xy -0.22733 -0.30353) (xy -0.2286 -0.2921) (xy -0.22733 -0.28067) (xy -0.22733 -0.27051)
						(xy -0.22606 -0.25908) (xy -0.22352 -0.24892) (xy -0.22225 -0.23876) (xy -0.21844 -0.22733) (xy -0.2159 -0.21717)
						(xy -0.21209 -0.20701) (xy -0.20701 -0.19685) (xy -0.2032 -0.18796) (xy -0.19812 -0.1778) (xy -0.17272 -0.14224)
						(xy -0.1651 -0.13462) (xy -0.1651 0.7366) (xy -0.16256 0.76835) (xy -0.1524 0.8001) (xy -0.13716 0.82804)
						(xy -0.11684 0.85344) (xy -0.09144 0.87376) (xy -0.0635 0.889) (xy -0.03175 0.89916) (xy 0 0.9017)
						(xy 0.03175 0.89916) (xy 0.0635 0.889) (xy 0.09144 0.87376) (xy 0.11684 0.85344) (xy 0.13716 0.82804)
						(xy 0.1524 0.8001) (xy 0.16256 0.76835) (xy 0.1651 0.7366) (xy 0.1651 -0.13462) (xy 0.17272 -0.14224)
						(xy 0.19812 -0.1778) (xy 0.2032 -0.18796) (xy 0.20701 -0.19685) (xy 0.21209 -0.20701) (xy 0.2159 -0.21717)
						(xy 0.21844 -0.22733) (xy 0.22225 -0.23876) (xy 0.22352 -0.24892) (xy 0.22606 -0.25908) (xy 0.22733 -0.27051)
						(xy 0.22733 -0.28067) (xy 0.2286 -0.2921) (xy 0.22733 -0.30353) (xy 0.22733 -0.31369) (xy 0.22606 -0.32512)
						(xy 0.22352 -0.33528) (xy 0.22225 -0.34544) (xy 0.21844 -0.35687) (xy 0.2159 -0.36703) (xy 0.21209 -0.37719)
						(xy 0.20701 -0.38735) (xy 0.2032 -0.39624) (xy 0.19812 -0.4064) (xy 0.17272 -0.44196) (xy 0.1651 -0.44958)
						(xy 0.1651 -0.7366) (xy 0.16256 -0.76835) (xy 0.1524 -0.8001) (xy 0.13716 -0.82804) (xy 0.11684 -0.85344)
						(xy 0.09144 -0.87376) (xy 0.0635 -0.889) (xy 0.03175 -0.89916)
					)
					(width 0)
					(fill yes)
				)
			)
		)
	)
)
